(kicad_pcb
	(version 20260206)
	(generator "pcbnew")
	(generator_version "10.0")
	(general
		(thickness 1.6)
		(legacy_teardrops no)
	)
	(paper "A4")
	(title_block
		(title "Bryce Canyon_IOM_IOC_16318-2_OCP.brd")
		(comment 1 "Bryce Canyon / footprints 1380-1387 of 1605")
	)
	(layers
		(0 "F.Cu" signal "TOP")
		(4 "In1.Cu" signal "L2GND")
		(6 "In2.Cu" signal "L3")
		(8 "In3.Cu" signal "L4VCC")
		(10 "In4.Cu" signal "L5VCC")
		(12 "In5.Cu" signal "L6")
		(14 "In6.Cu" signal "L7GND")
		(2 "B.Cu" signal "BOTTOM")
		(9 "F.Adhes" user "F.Adhesive")
		(11 "B.Adhes" user "B.Adhesive")
		(13 "F.Paste" user "Package Geometry/Pastemask Top")
		(15 "B.Paste" user "Package Geometry/Pastemask Bottom")
		(5 "F.SilkS" user "Ref Des/Silkscreen Top")
		(7 "B.SilkS" user "Ref Des/Silkscreen Bottom")
		(1 "F.Mask" user "Board Geometry/Soldermask Top")
		(3 "B.Mask" user "Board Geometry/Soldermask Bottom")
		(17 "Dwgs.User" user "User.Drawings")
		(19 "Cmts.User" user "User.Comments")
		(21 "Eco1.User" user "User.Eco1")
		(23 "Eco2.User" user "User.Eco2")
		(25 "Edge.Cuts" user "Board Geometry/Outline")
		(27 "Margin" user)
		(31 "F.CrtYd" user "Package Geometry/Place Bound Top")
		(29 "B.CrtYd" user "Package Geometry/Place Bound Bottom")
		(35 "F.Fab" user "Ref Des/Assembly Top")
		(33 "B.Fab" user "Ref Des/Assembly Bottom")
	)
	(footprint ""
		(layer "B.Cu")
		(at 209.042 -61.0108 -90)
		(property "Reference" "R588"
			(at 0 0 90)
			(layer "B.SilkS")
			(hide yes)
			(effects
				(font
					(size 1.27 1.27)
				)
				(justify mirror)
			)
		)
		(property "Value" "2K2R2F-GP"
			(at -0.064008 -3.993896 270)
			(unlocked yes)
			(layer "B.Fab")
			(hide yes)
			(effects
				(font
					(size 1.016 1.016)
					(thickness 0.1524)
				)
				(justify mirror)
			)
		)
		(property "Device Type" "R402H16"
			(at -0.064008 -5.517896 270)
			(unlocked yes)
			(layer "B.Fab")
			(hide yes)
			(effects
				(font
					(size 1.016 1.016)
					(thickness 0.1524)
				)
				(justify mirror)
			)
		)
		(duplicate_pad_numbers_are_jumpers no)
		(fp_line
			(start -0.508 -0.9398)
			(end 0.508 -0.9398)
			(stroke
				(width 0.1524)
				(type default)
			)
			(layer "B.SilkS")
		)
		(fp_line
			(start 0.508 -0.9398)
			(end 0.508 0.9398)
			(stroke
				(width 0.1524)
				(type default)
			)
			(layer "B.SilkS")
		)
		(fp_rect
			(start 0.508 0.9398)
			(end -0.508 -0.9398)
			(stroke
				(width 0)
				(type default)
			)
			(fill no)
			(layer "B.CrtYd")
		)
		(fp_rect
			(start 0.508 0.9398)
			(end -0.508 -0.9398)
			(stroke
				(width 0)
				(type default)
			)
			(fill no)
			(layer "B.Fab")
		)
		(pad "1" smd custom
			(at 0 -0.4445 90)
			(size 0.1397 0.1397)
			(layers "B.Cu" "B.Mask" "B.Paste")
			(net "P1V8")
			(options
				(clearance outline)
				(anchor circle)
			)
			(primitives
				(gr_poly
					(pts
						(arc
							(start -0.1778 0.2794)
							(mid -0.249642 0.249642)
							(end -0.2794 0.1778)
						)
						(arc
							(start -0.2794 -0.1778)
							(mid -0.249642 -0.249642)
							(end -0.1778 -0.2794)
						)
						(arc
							(start 0.1778 -0.2794)
							(mid 0.249642 -0.249642)
							(end 0.2794 -0.1778)
						)
						(arc
							(start 0.2794 0.1778)
							(mid 0.249642 0.249642)
							(end 0.1778 0.2794)
						)
					)
					(width 0)
					(fill yes)
				)
			)
		)
		(pad "2" smd custom
			(at 0 0.4445 90)
			(size 0.1397 0.1397)
			(layers "B.Cu" "B.Mask" "B.Paste")
			(net "SIO_CLK_0")
			(options
				(clearance outline)
				(anchor circle)
			)
			(primitives
				(gr_poly
					(pts
						(arc
							(start -0.1778 0.2794)
							(mid -0.249642 0.249642)
							(end -0.2794 0.1778)
						)
						(arc
							(start -0.2794 -0.1778)
							(mid -0.249642 -0.249642)
							(end -0.1778 -0.2794)
						)
						(arc
							(start 0.1778 -0.2794)
							(mid 0.249642 -0.249642)
							(end 0.2794 -0.1778)
						)
						(arc
							(start 0.2794 0.1778)
							(mid 0.249642 0.249642)
							(end 0.1778 0.2794)
						)
					)
					(width 0)
					(fill yes)
				)
			)
		)
	)
	(footprint ""
		(layer "B.Cu")
		(at 49.0855 -142.0495 -90)
		(property "Reference" "C83"
			(at 0 0 90)
			(layer "B.SilkS")
			(hide yes)
			(effects
				(font
					(size 1.27 1.27)
				)
				(justify mirror)
			)
		)
		(property "Value" "SC1U16V3KX-5GP"
			(at 0 -2.8194 270)
			(unlocked yes)
			(layer "B.Fab")
			(hide yes)
			(effects
				(font
					(size 1.016 1.016)
					(thickness 0.1524)
				)
				(justify mirror)
			)
		)
		(property "Device Type" "C603H36"
			(at 0 -4.3434 270)
			(unlocked yes)
			(layer "B.Fab")
			(hide yes)
			(effects
				(font
					(size 1.016 1.016)
					(thickness 0.1524)
				)
				(justify mirror)
			)
		)
		(duplicate_pad_numbers_are_jumpers no)
		(fp_line
			(start -0.508 0)
			(end 0.508 0)
			(stroke
				(width 0.2032)
				(type default)
			)
			(layer "B.SilkS")
		)
		(fp_rect
			(start 0.5842 1.3335)
			(end -0.5842 -1.3335)
			(stroke
				(width 0)
				(type default)
			)
			(fill no)
			(layer "B.CrtYd")
		)
		(fp_rect
			(start 0.5842 1.3335)
			(end -0.5842 -1.3335)
			(stroke
				(width 0)
				(type default)
			)
			(fill no)
			(layer "B.Fab")
		)
		(pad "1" smd custom
			(at 0 -0.762 90)
			(size 0.2159 0.2159)
			(layers "B.Cu" "B.Mask" "B.Paste")
			(net "JTAG_BMC_TRST_N")
			(options
				(clearance outline)
				(anchor circle)
			)
			(primitives
				(gr_poly
					(pts
						(arc
							(start -0.3302 0.4318)
							(mid -0.402042 0.402042)
							(end -0.4318 0.3302)
						)
						(arc
							(start -0.4318 -0.3302)
							(mid -0.402042 -0.402042)
							(end -0.3302 -0.4318)
						)
						(arc
							(start 0.3302 -0.4318)
							(mid 0.402042 -0.402042)
							(end 0.4318 -0.3302)
						)
						(arc
							(start 0.4318 0.3302)
							(mid 0.402042 0.402042)
							(end 0.3302 0.4318)
						)
					)
					(width 0)
					(fill yes)
				)
			)
		)
		(pad "2" smd custom
			(at 0 0.762 90)
			(size 0.2159 0.2159)
			(layers "B.Cu" "B.Mask" "B.Paste")
			(net "GND")
			(options
				(clearance outline)
				(anchor circle)
			)
			(primitives
				(gr_poly
					(pts
						(arc
							(start -0.3302 0.4318)
							(mid -0.402042 0.402042)
							(end -0.4318 0.3302)
						)
						(arc
							(start -0.4318 -0.3302)
							(mid -0.402042 -0.402042)
							(end -0.3302 -0.4318)
						)
						(arc
							(start 0.3302 -0.4318)
							(mid 0.402042 -0.402042)
							(end 0.4318 -0.3302)
						)
						(arc
							(start 0.4318 0.3302)
							(mid 0.402042 0.402042)
							(end 0.3302 0.4318)
						)
					)
					(width 0)
					(fill yes)
				)
			)
		)
	)
	(footprint ""
		(layer "B.Cu")
		(at 43.31843 -137.103866)
		(property "Reference" "TP27"
			(at 0 0 0)
			(layer "B.SilkS")
			(hide yes)
			(effects
				(font
					(size 1.27 1.27)
				)
				(justify mirror)
			)
		)
		(property "Value" "TPAD28-2-GP"
			(at 0.0127 -1.6637 0)
			(unlocked yes)
			(layer "B.Fab")
			(hide yes)
			(effects
				(font
					(size 1.016 1.016)
					(thickness 0.1524)
				)
				(justify mirror)
			)
		)
		(property "Device Type" "TPAD28"
			(at 0.0127 -3.1877 0)
			(unlocked yes)
			(layer "B.Fab")
			(hide yes)
			(effects
				(font
					(size 1.016 1.016)
					(thickness 0.1524)
				)
				(justify mirror)
			)
		)
		(duplicate_pad_numbers_are_jumpers no)
		(fp_poly
			(pts
				(arc
					(start 0.3556 0)
					(mid -0.3556 0)
					(end 0.3556 0)
				)
			)
			(stroke
				(width 0)
				(type default)
			)
			(fill no)
			(layer "B.CrtYd")
		)
		(fp_poly
			(pts
				(arc
					(start 0.6096 0)
					(mid -0.6096 0)
					(end 0.6096 0)
				)
			)
			(stroke
				(width 0)
				(type default)
			)
			(fill no)
			(layer "B.Fab")
		)
		(pad "1" smd circle
			(at 0 0 180)
			(size 0.7112 0.7112)
			(layers "B.Cu" "B.Mask" "B.Paste")
			(net "TP_BMC_GPIOR1")
		)
	)
	(footprint ""
		(layer "B.Cu")
		(at 47.4726 -135.7376 180)
		(property "Reference" "R140"
			(at 0 0 0)
			(layer "B.SilkS")
			(hide yes)
			(effects
				(font
					(size 1.27 1.27)
				)
				(justify mirror)
			)
		)
		(property "Value" "100KR2F-L1-GP"
			(at -0.064008 -3.993896 180)
			(unlocked yes)
			(layer "B.Fab")
			(hide yes)
			(effects
				(font
					(size 1.016 1.016)
					(thickness 0.1524)
				)
				(justify mirror)
			)
		)
		(property "Device Type" "R402H16"
			(at -0.064008 -5.517896 180)
			(unlocked yes)
			(layer "B.Fab")
			(hide yes)
			(effects
				(font
					(size 1.016 1.016)
					(thickness 0.1524)
				)
				(justify mirror)
			)
		)
		(duplicate_pad_numbers_are_jumpers no)
		(fp_line
			(start 0.508 -0.9398)
			(end 0.508 0.9398)
			(stroke
				(width 0.1524)
				(type default)
			)
			(layer "B.SilkS")
		)
		(fp_line
			(start -0.508 -0.9398)
			(end 0.508 -0.9398)
			(stroke
				(width 0.1524)
				(type default)
			)
			(layer "B.SilkS")
		)
		(fp_rect
			(start 0.508 0.9398)
			(end -0.508 -0.9398)
			(stroke
				(width 0)
				(type default)
			)
			(fill no)
			(layer "B.CrtYd")
		)
		(fp_rect
			(start 0.508 0.9398)
			(end -0.508 -0.9398)
			(stroke
				(width 0)
				(type default)
			)
			(fill no)
			(layer "B.Fab")
		)
		(pad "1" smd custom
			(at 0 -0.4445)
			(size 0.1397 0.1397)
			(layers "B.Cu" "B.Mask" "B.Paste")
			(net "GND")
			(options
				(clearance outline)
				(anchor circle)
			)
			(primitives
				(gr_poly
					(pts
						(arc
							(start -0.1778 0.2794)
							(mid -0.249642 0.249642)
							(end -0.2794 0.1778)
						)
						(arc
							(start -0.2794 -0.1778)
							(mid -0.249642 -0.249642)
							(end -0.1778 -0.2794)
						)
						(arc
							(start 0.1778 -0.2794)
							(mid 0.249642 -0.249642)
							(end 0.2794 -0.1778)
						)
						(arc
							(start 0.2794 0.1778)
							(mid 0.249642 0.249642)
							(end 0.1778 0.2794)
						)
					)
					(width 0)
					(fill yes)
				)
			)
		)
		(pad "2" smd custom
			(at 0 0.4445)
			(size 0.1397 0.1397)
			(layers "B.Cu" "B.Mask" "B.Paste")
			(net "PD_PERST_N")
			(options
				(clearance outline)
				(anchor circle)
			)
			(primitives
				(gr_poly
					(pts
						(arc
							(start -0.1778 0.2794)
							(mid -0.249642 0.249642)
							(end -0.2794 0.1778)
						)
						(arc
							(start -0.2794 -0.1778)
							(mid -0.249642 -0.249642)
							(end -0.1778 -0.2794)
						)
						(arc
							(start 0.1778 -0.2794)
							(mid 0.249642 -0.249642)
							(end 0.2794 -0.1778)
						)
						(arc
							(start 0.2794 0.1778)
							(mid 0.249642 0.249642)
							(end 0.1778 0.2794)
						)
					)
					(width 0)
					(fill yes)
				)
			)
		)
	)
	(footprint ""
		(layer "B.Cu")
		(at 12.091924 -136.715246 90)
		(property "Reference" "R251"
			(at 0 0 90)
			(layer "B.SilkS")
			(hide yes)
			(effects
				(font
					(size 1.27 1.27)
				)
				(justify mirror)
			)
		)
		(property "Value" "120R2F-GP"
			(at -0.064008 -3.993896 90)
			(unlocked yes)
			(layer "B.Fab")
			(hide yes)
			(effects
				(font
					(size 1.016 1.016)
					(thickness 0.1524)
				)
				(justify mirror)
			)
		)
		(property "Device Type" "R402H16"
			(at -0.064008 -5.517896 90)
			(unlocked yes)
			(layer "B.Fab")
			(hide yes)
			(effects
				(font
					(size 1.016 1.016)
					(thickness 0.1524)
				)
				(justify mirror)
			)
		)
		(duplicate_pad_numbers_are_jumpers no)
		(fp_line
			(start 0.508 -0.9398)
			(end 0.508 0.9398)
			(stroke
				(width 0.1524)
				(type default)
			)
			(layer "B.SilkS")
		)
		(fp_line
			(start -0.508 -0.9398)
			(end 0.508 -0.9398)
			(stroke
				(width 0.1524)
				(type default)
			)
			(layer "B.SilkS")
		)
		(fp_rect
			(start 0.508 0.9398)
			(end -0.508 -0.9398)
			(stroke
				(width 0)
				(type default)
			)
			(fill no)
			(layer "B.CrtYd")
		)
		(fp_rect
			(start 0.508 0.9398)
			(end -0.508 -0.9398)
			(stroke
				(width 0)
				(type default)
			)
			(fill no)
			(layer "B.Fab")
		)
		(pad "1" smd custom
			(at 0 -0.4445 270)
			(size 0.1397 0.1397)
			(layers "B.Cu" "B.Mask" "B.Paste")
			(net "MEMA_8")
			(options
				(clearance outline)
				(anchor circle)
			)
			(primitives
				(gr_poly
					(pts
						(arc
							(start -0.1778 0.2794)
							(mid -0.249642 0.249642)
							(end -0.2794 0.1778)
						)
						(arc
							(start -0.2794 -0.1778)
							(mid -0.249642 -0.249642)
							(end -0.1778 -0.2794)
						)
						(arc
							(start 0.1778 -0.2794)
							(mid 0.249642 -0.249642)
							(end 0.2794 -0.1778)
						)
						(arc
							(start 0.2794 0.1778)
							(mid 0.249642 0.249642)
							(end 0.1778 0.2794)
						)
					)
					(width 0)
					(fill yes)
				)
			)
		)
		(pad "2" smd custom
			(at 0 0.4445 270)
			(size 0.1397 0.1397)
			(layers "B.Cu" "B.Mask" "B.Paste")
			(net "P1V2_STBY")
			(options
				(clearance outline)
				(anchor circle)
			)
			(primitives
				(gr_poly
					(pts
						(arc
							(start -0.1778 0.2794)
							(mid -0.249642 0.249642)
							(end -0.2794 0.1778)
						)
						(arc
							(start -0.2794 -0.1778)
							(mid -0.249642 -0.249642)
							(end -0.1778 -0.2794)
						)
						(arc
							(start 0.1778 -0.2794)
							(mid 0.249642 -0.249642)
							(end 0.2794 -0.1778)
						)
						(arc
							(start 0.2794 0.1778)
							(mid 0.249642 0.249642)
							(end 0.1778 0.2794)
						)
					)
					(width 0)
					(fill yes)
				)
			)
		)
	)
	(footprint ""
		(layer "B.Cu")
		(at 69.46646 -148.869908)
		(property "Reference" "R381"
			(at 0 0 0)
			(layer "B.SilkS")
			(hide yes)
			(effects
				(font
					(size 1.27 1.27)
				)
				(justify mirror)
			)
		)
		(property "Value" "4K7R2F-GP"
			(at -0.064008 -3.993896 0)
			(unlocked yes)
			(layer "B.Fab")
			(hide yes)
			(effects
				(font
					(size 1.016 1.016)
					(thickness 0.1524)
				)
				(justify mirror)
			)
		)
		(property "Device Type" "R402H16"
			(at -0.064008 -5.517896 0)
			(unlocked yes)
			(layer "B.Fab")
			(hide yes)
			(effects
				(font
					(size 1.016 1.016)
					(thickness 0.1524)
				)
				(justify mirror)
			)
		)
		(duplicate_pad_numbers_are_jumpers no)
		(fp_line
			(start -0.508 -0.9398)
			(end 0.508 -0.9398)
			(stroke
				(width 0.1524)
				(type default)
			)
			(layer "B.SilkS")
		)
		(fp_line
			(start 0.508 -0.9398)
			(end 0.508 0.9398)
			(stroke
				(width 0.1524)
				(type default)
			)
			(layer "B.SilkS")
		)
		(fp_rect
			(start 0.508 0.9398)
			(end -0.508 -0.9398)
			(stroke
				(width 0)
				(type default)
			)
			(fill no)
			(layer "B.CrtYd")
		)
		(fp_rect
			(start 0.508 0.9398)
			(end -0.508 -0.9398)
			(stroke
				(width 0)
				(type default)
			)
			(fill no)
			(layer "B.Fab")
		)
		(pad "1" smd custom
			(at 0 -0.4445 180)
			(size 0.1397 0.1397)
			(layers "B.Cu" "B.Mask" "B.Paste")
			(net "P3V3_STBY")
			(options
				(clearance outline)
				(anchor circle)
			)
			(primitives
				(gr_poly
					(pts
						(arc
							(start -0.1778 0.2794)
							(mid -0.249642 0.249642)
							(end -0.2794 0.1778)
						)
						(arc
							(start -0.2794 -0.1778)
							(mid -0.249642 -0.249642)
							(end -0.1778 -0.2794)
						)
						(arc
							(start 0.1778 -0.2794)
							(mid 0.249642 -0.249642)
							(end 0.2794 -0.1778)
						)
						(arc
							(start 0.2794 0.1778)
							(mid 0.249642 0.249642)
							(end 0.1778 0.2794)
						)
					)
					(width 0)
					(fill yes)
				)
			)
		)
		(pad "2" smd custom
			(at 0 0.4445 180)
			(size 0.1397 0.1397)
			(layers "B.Cu" "B.Mask" "B.Paste")
			(net "NCSI_TXD0")
			(options
				(clearance outline)
				(anchor circle)
			)
			(primitives
				(gr_poly
					(pts
						(arc
							(start -0.1778 0.2794)
							(mid -0.249642 0.249642)
							(end -0.2794 0.1778)
						)
						(arc
							(start -0.2794 -0.1778)
							(mid -0.249642 -0.249642)
							(end -0.1778 -0.2794)
						)
						(arc
							(start 0.1778 -0.2794)
							(mid 0.249642 -0.249642)
							(end 0.2794 -0.1778)
						)
						(arc
							(start 0.2794 0.1778)
							(mid 0.249642 0.249642)
							(end 0.1778 0.2794)
						)
					)
					(width 0)
					(fill yes)
				)
			)
		)
	)
	(footprint ""
		(layer "B.Cu")
		(at 44.4246 -128.2192 180)
		(property "Reference" "R371"
			(at 0 0 0)
			(layer "B.SilkS")
			(hide yes)
			(effects
				(font
					(size 1.27 1.27)
				)
				(justify mirror)
			)
		)
		(property "Value" "4K7R2F-GP"
			(at -0.064008 -3.993896 180)
			(unlocked yes)
			(layer "B.Fab")
			(hide yes)
			(effects
				(font
					(size 1.016 1.016)
					(thickness 0.1524)
				)
				(justify mirror)
			)
		)
		(property "Device Type" "R402H16"
			(at -0.064008 -5.517896 180)
			(unlocked yes)
			(layer "B.Fab")
			(hide yes)
			(effects
				(font
					(size 1.016 1.016)
					(thickness 0.1524)
				)
				(justify mirror)
			)
		)
		(duplicate_pad_numbers_are_jumpers no)
		(fp_line
			(start 0.508 -0.9398)
			(end 0.508 0.9398)
			(stroke
				(width 0.1524)
				(type default)
			)
			(layer "B.SilkS")
		)
		(fp_line
			(start -0.508 -0.9398)
			(end 0.508 -0.9398)
			(stroke
				(width 0.1524)
				(type default)
			)
			(layer "B.SilkS")
		)
		(fp_rect
			(start 0.508 0.9398)
			(end -0.508 -0.9398)
			(stroke
				(width 0)
				(type default)
			)
			(fill no)
			(layer "B.CrtYd")
		)
		(fp_rect
			(start 0.508 0.9398)
			(end -0.508 -0.9398)
			(stroke
				(width 0)
				(type default)
			)
			(fill no)
			(layer "B.Fab")
		)
		(pad "1" smd custom
			(at 0 -0.4445)
			(size 0.1397 0.1397)
			(layers "B.Cu" "B.Mask" "B.Paste")
			(net "P3V3_STBY")
			(options
				(clearance outline)
				(anchor circle)
			)
			(primitives
				(gr_poly
					(pts
						(arc
							(start -0.1778 0.2794)
							(mid -0.249642 0.249642)
							(end -0.2794 0.1778)
						)
						(arc
							(start -0.2794 -0.1778)
							(mid -0.249642 -0.249642)
							(end -0.1778 -0.2794)
						)
						(arc
							(start 0.1778 -0.2794)
							(mid 0.249642 -0.249642)
							(end 0.2794 -0.1778)
						)
						(arc
							(start 0.2794 0.1778)
							(mid 0.249642 0.249642)
							(end 0.1778 0.2794)
						)
					)
					(width 0)
					(fill yes)
				)
			)
		)
		(pad "2" smd custom
			(at 0 0.4445)
			(size 0.1397 0.1397)
			(layers "B.Cu" "B.Mask" "B.Paste")
			(net "BMC_SPI_MISO")
			(options
				(clearance outline)
				(anchor circle)
			)
			(primitives
				(gr_poly
					(pts
						(arc
							(start -0.1778 0.2794)
							(mid -0.249642 0.249642)
							(end -0.2794 0.1778)
						)
						(arc
							(start -0.2794 -0.1778)
							(mid -0.249642 -0.249642)
							(end -0.1778 -0.2794)
						)
						(arc
							(start 0.1778 -0.2794)
							(mid 0.249642 -0.249642)
							(end 0.2794 -0.1778)
						)
						(arc
							(start 0.2794 0.1778)
							(mid 0.249642 0.249642)
							(end 0.1778 0.2794)
						)
					)
					(width 0)
					(fill yes)
				)
			)
		)
	)
	(footprint ""
		(layer "B.Cu")
		(at 189.2554 -65.3796 90)
		(property "Reference" "C399"
			(at 0 0 90)
			(layer "B.SilkS")
			(hide yes)
			(effects
				(font
					(size 1.27 1.27)
				)
				(justify mirror)
			)
		)
		(property "Value" "SCD1U6D3V1KX-GP"
			(at 2.8321 -1.7399 90)
			(unlocked yes)
			(layer "B.Fab")
			(hide yes)
			(effects
				(font
					(size 1.016 1.016)
					(thickness 0.1524)
				)
				(justify mirror)
			)
		)
		(property "Device Type" "C0201H13"
			(at 2.8321 -3.2639 90)
			(unlocked yes)
			(layer "B.Fab")
			(hide yes)
			(effects
				(font
					(size 1.016 1.016)
					(thickness 0.1524)
				)
				(justify mirror)
			)
		)
		(duplicate_pad_numbers_are_jumpers no)
		(fp_rect
			(start 0.2794 0.6477)
			(end -0.2794 -0.6477)
			(stroke
				(width 0)
				(type default)
			)
			(fill no)
			(layer "B.CrtYd")
		)
		(fp_rect
			(start 0.2794 0.6477)
			(end -0.2794 -0.6477)
			(stroke
				(width 0)
				(type default)
			)
			(fill no)
			(layer "B.Fab")
		)
		(pad "1" smd custom
			(at 0 -0.2794 270)
			(size 0.0762 0.0762)
			(layers "B.Cu" "B.Mask" "B.Paste")
			(net "P0V975")
			(options
				(clearance outline)
				(anchor circle)
			)
			(primitives
				(gr_poly
					(pts
						(arc
							(start 0.1524 0.127)
							(mid 0.137521 0.162921)
							(end 0.1016 0.1778)
						)
						(arc
							(start -0.1016 0.1778)
							(mid -0.137521 0.162921)
							(end -0.1524 0.127)
						)
						(arc
							(start -0.1524 -0.127)
							(mid -0.137521 -0.162921)
							(end -0.1016 -0.1778)
						)
						(arc
							(start 0.1016 -0.1778)
							(mid 0.137521 -0.162921)
							(end 0.1524 -0.127)
						)
					)
					(width 0)
					(fill yes)
				)
			)
		)
		(pad "2" smd custom
			(at 0 0.2794 270)
			(size 0.0762 0.0762)
			(layers "B.Cu" "B.Mask" "B.Paste")
			(net "GND")
			(options
				(clearance outline)
				(anchor circle)
			)
			(primitives
				(gr_poly
					(pts
						(arc
							(start 0.1524 0.127)
							(mid 0.137521 0.162921)
							(end 0.1016 0.1778)
						)
						(arc
							(start -0.1016 0.1778)
							(mid -0.137521 0.162921)
							(end -0.1524 0.127)
						)
						(arc
							(start -0.1524 -0.127)
							(mid -0.137521 -0.162921)
							(end -0.1016 -0.1778)
						)
						(arc
							(start 0.1016 -0.1778)
							(mid 0.137521 -0.162921)
							(end 0.1524 -0.127)
						)
					)
					(width 0)
					(fill yes)
				)
			)
		)
	)
)
